(kicad_pcb
	(version 20211014)
	(generator pcbnew)
	(general
    (thickness 1.6)
  )
	(paper "A4")
	(title_block
    (title "SA800U (Snapdragon 845) Baseboard")
    (date "2023-10-19")
    (rev "1.0.3")
    (company "Antmicro Ltd.")
    (comment 1 "www.antmicro.com")
		(comment 9 "footprints 408-415 of 589")
	)
	(layers
    (0 "F.Cu" signal)
    (1 "In1.Cu" power)
    (2 "In2.Cu" signal)
    (3 "In3.Cu" signal)
    (4 "In4.Cu" power)
    (31 "B.Cu" signal)
    (32 "B.Adhes" user "B.Adhesive")
    (33 "F.Adhes" user "F.Adhesive")
    (34 "B.Paste" user)
    (35 "F.Paste" user)
    (36 "B.SilkS" user "B.Silkscreen")
    (37 "F.SilkS" user "F.Silkscreen")
    (38 "B.Mask" user)
    (39 "F.Mask" user)
    (40 "Dwgs.User" user "User.Drawings")
    (41 "Cmts.User" user "User.Comments")
    (42 "Eco1.User" user "User.Eco1")
    (43 "Eco2.User" user "User.Eco2")
    (44 "Edge.Cuts" user)
    (45 "Margin" user)
    (46 "B.CrtYd" user "B.Courtyard")
    (47 "F.CrtYd" user "F.Courtyard")
    (48 "B.Fab" user)
    (49 "F.Fab" user)
  )
	(footprint "sa800u-baseboard-hw-footprints:C_0402_1005Metric" (layer "B.Cu")
    (tedit 616D63CF)
    (at 114.25 138.95 -90)
    (descr "Capacitor SMD 0402")
    (tags "capacitor SMD 0402")
    (property "Author" "Antmicro")
    (property "Dielectric" "X5R")
    (property "License" "Apache-2.0")
    (property "MPN" "GRM155R61H104KE14D")
    (property "Manufacturer" "Murata")
    (property "Sheetfile" "usb-c-interface.kicad_sch")
    (property "Sheetname" "USB-C Interface ")
    (property "Val" "100n")
    (property "Voltage" "50V")
    (attr smd)
    (fp_text reference "C85" (at -3.05 -0.34 90) (layer "B.SilkS")
      (effects (font (size 0.7 0.7) (thickness 0.15)) (justify left bottom mirror))
    )
    (fp_text value "C_100n_0402" (at 0 -1.4 90) (layer "B.Fab")
      (effects (font (size 0.7 0.7) (thickness 0.15)) (justify left bottom mirror))
    )
    (fp_text user "${REFERENCE}" (at -0.932 -3.168 90) (layer "B.Fab") hide
      (effects (font (size 0.7 0.7) (thickness 0.15)) (justify left bottom mirror))
    )
    (fp_text user "Author: Antmicro" (at -0.932 -4.17 90) (layer "B.Fab") hide
      (effects (font (size 0.7 0.7) (thickness 0.15)) (justify left bottom mirror))
    )
    (fp_text user "License: Apache-2.0" (at -0.932 -5.17 90) (layer "B.Fab") hide
      (effects (font (size 0.7 0.7) (thickness 0.15)) (justify left bottom mirror))
    )
    (fp_rect (start -0.94 0.47) (end 0.94 -0.47) (layer "B.CrtYd") (width 0.05) (fill none))
    (fp_rect (start -0.499 0.249) (end 0.499 -0.249) (layer "B.Fab") (width 0.15) (fill none))
    (pad "1" smd roundrect (at -0.484 0 270) (size 0.59 0.64) (layers "B.Cu" "B.Paste" "B.Mask") (roundrect_rratio 0.25)
      (net 216 "/USB-C Interface /USB2C_TX1_P") (pintype "passive"))
    (pad "2" smd roundrect (at 0.484 0 270) (size 0.59 0.64) (layers "B.Cu" "B.Paste" "B.Mask") (roundrect_rratio 0.25)
      (net 215 "/USB-C Interface /USB2C_TX1_C_P") (pintype "passive"))
  )
	(footprint "sa800u-baseboard-hw-footprints:Nexperia_DFN-10_2.5x1mm_P0.5mm" (layer "B.Cu")
    (tedit 6215DC23)
    (at 101.75 140.6 180)
    (property "Author" "Antmicro")
    (property "License" "Apache-2.0")
    (property "MPN" "PUSB3F96X")
    (property "Manufacturer" "Nexperia")
    (property "Sheetfile" "usb-c-interface.kicad_sch")
    (property "Sheetname" "USB-C Interface ")
    (attr smd)
    (fp_text reference "D8" (at -0.66 -1.69) (layer "B.SilkS")
      (effects (font (size 0.7 0.7) (thickness 0.15)) (justify left bottom mirror))
    )
    (fp_text value "PUSB3F96X_PASS" (at -0.016 -1.705) (layer "B.Fab")
      (effects (font (size 0.7 0.7) (thickness 0.15)) (justify left bottom mirror))
    )
    (fp_text user "Author: Antmicro" (at -1.367 -4.905) (layer "B.Fab") hide
      (effects (font (size 0.7 0.7) (thickness 0.15)) (justify left bottom mirror))
    )
    (fp_text user "${REFERENCE}" (at -1.367 -3.704) (layer "B.Fab") hide
      (effects (font (size 0.7 0.7) (thickness 0.15)) (justify left bottom mirror))
    )
    (fp_text user "License: Apache-2.0" (at -1.367 -6.105) (layer "B.Fab") hide
      (effects (font (size 0.7 0.7) (thickness 0.15)) (justify left bottom mirror))
    )
    (fp_line (start 1.233 -0.405) (end 1.233 0.396) (layer "B.SilkS") (width 0.15))
    (fp_line (start -1.266 0.396) (end -1.266 -0.405) (layer "B.SilkS") (width 0.15))
    (fp_circle (center -1.317 -0.704) (end -1.266 -0.704) (layer "B.SilkS") (width 0.15) (fill solid))
    (fp_rect (start -1.4 0.7) (end 1.4 -0.7) (layer "B.CrtYd") (width 0.05) (fill none))
    (pad "1" smd rect (at -1.016 -0.392 180) (size 0.2 0.475) (layers "B.Cu" "B.Paste" "B.Mask")
      (net 327 "USB_CC2") (pinfunction "CH1") (pintype "passive"))
    (pad "2" smd rect (at -0.517 -0.392 180) (size 0.2 0.475) (layers "B.Cu" "B.Paste" "B.Mask")
      (net 322 "USB1_D_N") (pinfunction "CH2") (pintype "passive"))
    (pad "3" smd rect (at -0.016 -0.392 180) (size 0.2 0.475) (layers "B.Cu" "B.Paste" "B.Mask")
      (net 1 "GND") (pinfunction "GND") (pintype "passive"))
    (pad "4" smd rect (at 0.482 -0.392 180) (size 0.2 0.475) (layers "B.Cu" "B.Paste" "B.Mask")
      (net 321 "USB1_D_P") (pinfunction "CH3") (pintype "passive"))
    (pad "5" smd rect (at 0.982 -0.392 180) (size 0.2 0.475) (layers "B.Cu" "B.Paste" "B.Mask")
      (net 326 "USB_CC1") (pinfunction "CH4") (pintype "passive"))
    (pad "6" smd rect (at 0.982 0.383) (size 0.2 0.475) (layers "B.Cu" "B.Paste" "B.Mask")
      (net 326 "USB_CC1") (pinfunction "CH4") (pintype "passive"))
    (pad "7" smd rect (at 0.482 0.383) (size 0.2 0.475) (layers "B.Cu" "B.Paste" "B.Mask")
      (net 321 "USB1_D_P") (pinfunction "CH3") (pintype "passive"))
    (pad "8" smd rect (at -0.016 0.383) (size 0.2 0.475) (layers "B.Cu" "B.Paste" "B.Mask")
      (net 1 "GND") (pinfunction "GND") (pintype "passive"))
    (pad "9" smd rect (at -0.517 0.383) (size 0.2 0.475) (layers "B.Cu" "B.Paste" "B.Mask")
      (net 322 "USB1_D_N") (pinfunction "CH2") (pintype "passive"))
    (pad "10" smd rect (at -1.016 0.383) (size 0.2 0.475) (layers "B.Cu" "B.Paste" "B.Mask")
      (net 327 "USB_CC2") (pinfunction "CH1") (pintype "passive"))
  )
	(footprint "sa800u-baseboard-hw-footprints:Nexperia_DFN-10_2.5x1mm_P0.5mm" (layer "B.Cu")
    (tedit 6215DC23)
    (at 104.5 140.6)
    (property "Author" "Antmicro")
    (property "License" "Apache-2.0")
    (property "MPN" "PUSB3F96X")
    (property "Manufacturer" "Nexperia")
    (property "Sheetfile" "usb-c-interface.kicad_sch")
    (property "Sheetname" "USB-C Interface ")
    (attr smd)
    (fp_text reference "D10" (at 0.72 1.57 180) (layer "B.SilkS")
      (effects (font (size 0.7 0.7) (thickness 0.15)) (justify left bottom mirror))
    )
    (fp_text value "PUSB3F96X_PASS" (at -0.016 -1.705 180) (layer "B.Fab")
      (effects (font (size 0.7 0.7) (thickness 0.15)) (justify left bottom mirror))
    )
    (fp_text user "Author: Antmicro" (at -1.367 -4.905 180) (layer "B.Fab") hide
      (effects (font (size 0.7 0.7) (thickness 0.15)) (justify left bottom mirror))
    )
    (fp_text user "License: Apache-2.0" (at -1.367 -6.105 180) (layer "B.Fab") hide
      (effects (font (size 0.7 0.7) (thickness 0.15)) (justify left bottom mirror))
    )
    (fp_text user "${REFERENCE}" (at -1.367 -3.704 180) (layer "B.Fab") hide
      (effects (font (size 0.7 0.7) (thickness 0.15)) (justify left bottom mirror))
    )
    (fp_line (start 1.233 -0.405) (end 1.233 0.396) (layer "B.SilkS") (width 0.15))
    (fp_line (start -1.266 0.396) (end -1.266 -0.405) (layer "B.SilkS") (width 0.15))
    (fp_circle (center -1.317 -0.704) (end -1.266 -0.704) (layer "B.SilkS") (width 0.15) (fill solid))
    (fp_rect (start -1.4 0.7) (end 1.4 -0.7) (layer "B.CrtYd") (width 0.05) (fill none))
    (pad "1" smd rect (at -1.016 -0.392) (size 0.2 0.475) (layers "B.Cu" "B.Paste" "B.Mask")
      (net 304 "/USB-C Interface /USB1C_RX1_C_N") (pinfunction "CH1") (pintype "passive"))
    (pad "2" smd rect (at -0.517 -0.392) (size 0.2 0.475) (layers "B.Cu" "B.Paste" "B.Mask")
      (net 305 "/USB-C Interface /USB1C_RX1_C_P") (pinfunction "CH2") (pintype "passive"))
    (pad "3" smd rect (at -0.016 -0.392) (size 0.2 0.475) (layers "B.Cu" "B.Paste" "B.Mask")
      (net 1 "GND") (pinfunction "GND") (pintype "passive"))
    (pad "4" smd rect (at 0.482 -0.392) (size 0.2 0.475) (layers "B.Cu" "B.Paste" "B.Mask")
      (net 306 "/USB-C Interface /USB1C_TX1_C_N") (pinfunction "CH3") (pintype "passive"))
    (pad "5" smd rect (at 0.982 -0.392) (size 0.2 0.475) (layers "B.Cu" "B.Paste" "B.Mask")
      (net 307 "/USB-C Interface /USB1C_TX1_C_P") (pinfunction "CH4") (pintype "passive"))
    (pad "6" smd rect (at 0.982 0.383 180) (size 0.2 0.475) (layers "B.Cu" "B.Paste" "B.Mask")
      (net 307 "/USB-C Interface /USB1C_TX1_C_P") (pinfunction "CH4") (pintype "passive"))
    (pad "7" smd rect (at 0.482 0.383 180) (size 0.2 0.475) (layers "B.Cu" "B.Paste" "B.Mask")
      (net 306 "/USB-C Interface /USB1C_TX1_C_N") (pinfunction "CH3") (pintype "passive"))
    (pad "8" smd rect (at -0.016 0.383 180) (size 0.2 0.475) (layers "B.Cu" "B.Paste" "B.Mask")
      (net 1 "GND") (pinfunction "GND") (pintype "passive"))
    (pad "9" smd rect (at -0.517 0.383 180) (size 0.2 0.475) (layers "B.Cu" "B.Paste" "B.Mask")
      (net 305 "/USB-C Interface /USB1C_RX1_C_P") (pinfunction "CH2") (pintype "passive"))
    (pad "10" smd rect (at -1.016 0.383 180) (size 0.2 0.475) (layers "B.Cu" "B.Paste" "B.Mask")
      (net 304 "/USB-C Interface /USB1C_RX1_C_N") (pinfunction "CH1") (pintype "passive"))
  )
	(footprint "sa800u-baseboard-hw-footprints:C_0402_1005Metric" (layer "B.Cu")
    (tedit 616D63CF)
    (at 125 133.9 180)
    (descr "Capacitor SMD 0402")
    (tags "capacitor SMD 0402")
    (property "Author" "Antmicro")
    (property "Dielectric" "X5R")
    (property "License" "Apache-2.0")
    (property "MPN" "GRM155R61H104KE14D")
    (property "Manufacturer" "Murata")
    (property "Sheetfile" "usb-c-interface.kicad_sch")
    (property "Sheetname" "USB-C Interface ")
    (property "Val" "100n")
    (property "Voltage" "50V")
    (attr smd)
    (fp_text reference "C64" (at -0.99 0.61) (layer "B.SilkS")
      (effects (font (size 0.7 0.7) (thickness 0.15)) (justify left bottom mirror))
    )
    (fp_text value "C_100n_0402" (at 0 -1.4) (layer "B.Fab")
      (effects (font (size 0.7 0.7) (thickness 0.15)) (justify left bottom mirror))
    )
    (fp_text user "${REFERENCE}" (at -0.932 -3.168) (layer "B.Fab") hide
      (effects (font (size 0.7 0.7) (thickness 0.15)) (justify left bottom mirror))
    )
    (fp_text user "License: Apache-2.0" (at -0.932 -5.17) (layer "B.Fab") hide
      (effects (font (size 0.7 0.7) (thickness 0.15)) (justify left bottom mirror))
    )
    (fp_text user "Author: Antmicro" (at -0.932 -4.17) (layer "B.Fab") hide
      (effects (font (size 0.7 0.7) (thickness 0.15)) (justify left bottom mirror))
    )
    (fp_rect (start -0.94 0.47) (end 0.94 -0.47) (layer "B.CrtYd") (width 0.05) (fill none))
    (fp_rect (start -0.499 0.249) (end 0.499 -0.249) (layer "B.Fab") (width 0.15) (fill none))
    (pad "1" smd roundrect (at -0.484 0 180) (size 0.59 0.64) (layers "B.Cu" "B.Paste" "B.Mask") (roundrect_rratio 0.25)
      (net 127 "1V8_DBG") (pintype "passive"))
    (pad "2" smd roundrect (at 0.484 0 180) (size 0.59 0.64) (layers "B.Cu" "B.Paste" "B.Mask") (roundrect_rratio 0.25)
      (net 1 "GND") (pintype "passive"))
  )
	(footprint "sa800u-baseboard-hw-footprints:C_0603_1608Metric" (layer "B.Cu")
    (tedit 5D5E94D2)
    (at 127.7 137.95 90)
    (descr "Capacitor SMD 0603")
    (tags "capacitor 0603")
    (property "Author" "Antmicro")
    (property "Dielectric" "")
    (property "License" "Apache-2.0")
    (property "MPN" "C1608X5R1V225K080AC")
    (property "Manufacturer" "TDK")
    (property "Sheetfile" "usb-c-interface.kicad_sch")
    (property "Sheetname" "USB-C Interface ")
    (property "Val" "2u2")
    (property "Voltage" "")
    (attr smd)
    (fp_text reference "C77" (at 1.13 1.37 270) (layer "B.SilkS")
      (effects (font (size 0.7 0.7) (thickness 0.15)) (justify left bottom mirror))
    )
    (fp_text value "C_2u2_0603" (at 0 -1.6 270) (layer "B.Fab")
      (effects (font (size 0.7 0.7) (thickness 0.15)) (justify left bottom mirror))
    )
    (fp_text user "License: Apache-2.0" (at -1.682 -5.895 270) (layer "B.Fab") hide
      (effects (font (size 0.7 0.7) (thickness 0.15)) (justify left bottom mirror))
    )
    (fp_text user "Author: Antmicro" (at -1.682 -4.894 270) (layer "B.Fab") hide
      (effects (font (size 0.7 0.7) (thickness 0.15)) (justify left bottom mirror))
    )
    (fp_text user "${REFERENCE}" (at -1.682 -3.895 270) (layer "B.Fab") hide
      (effects (font (size 0.7 0.7) (thickness 0.15)) (justify left bottom mirror))
    )
    (fp_line (start -0.3 0.3) (end 0.3 0.3) (layer "B.SilkS") (width 0.15))
    (fp_line (start -0.3 -0.3) (end 0.3 -0.3) (layer "B.SilkS") (width 0.15))
    (fp_rect (start -1.24 0.7) (end 1.24 -0.7) (layer "B.CrtYd") (width 0.05) (fill none))
    (fp_rect (start -0.8 0.4) (end 0.8 -0.4) (layer "B.Fab") (width 0.15) (fill none))
    (pad "1" smd roundrect (at -0.7 0 90) (size 0.6 0.8) (layers "B.Cu" "B.Paste" "B.Mask") (roundrect_rratio 0.2)
      (net 228 "/USB-C Interface /5V0_DBG") (pintype "passive"))
    (pad "2" smd roundrect (at 0.7 0 90) (size 0.6 0.8) (layers "B.Cu" "B.Paste" "B.Mask") (roundrect_rratio 0.2)
      (net 1 "GND") (pintype "passive"))
  )
	(footprint "sa800u-baseboard-hw-footprints:C_0402_1005Metric" (layer "B.Cu")
    (tedit 616D63CF)
    (at 131.4 142.25)
    (descr "Capacitor SMD 0402")
    (tags "capacitor SMD 0402")
    (property "Author" "Antmicro")
    (property "Dielectric" "C0G")
    (property "License" "Apache-2.0")
    (property "MPN" "GRM1555C1E470JA01D")
    (property "Manufacturer" "Murata")
    (property "Sheetfile" "usb-c-interface.kicad_sch")
    (property "Sheetname" "USB-C Interface ")
    (property "Val" "47p")
    (property "Voltage" "")
    (attr smd)
    (fp_text reference "C68" (at 1.05 -0.56 180) (layer "B.SilkS")
      (effects (font (size 0.7 0.7) (thickness 0.15)) (justify left bottom mirror))
    )
    (fp_text value "C_47p_0402" (at 0 -1.4 180) (layer "B.Fab")
      (effects (font (size 0.7 0.7) (thickness 0.15)) (justify left bottom mirror))
    )
    (fp_text user "Author: Antmicro" (at -0.932 -4.17 180) (layer "B.Fab") hide
      (effects (font (size 0.7 0.7) (thickness 0.15)) (justify left bottom mirror))
    )
    (fp_text user "License: Apache-2.0" (at -0.932 -5.17 180) (layer "B.Fab") hide
      (effects (font (size 0.7 0.7) (thickness 0.15)) (justify left bottom mirror))
    )
    (fp_text user "${REFERENCE}" (at -0.932 -3.168 180) (layer "B.Fab") hide
      (effects (font (size 0.7 0.7) (thickness 0.15)) (justify left bottom mirror))
    )
    (fp_rect (start -0.94 0.47) (end 0.94 -0.47) (layer "B.CrtYd") (width 0.05) (fill none))
    (fp_rect (start -0.499 0.249) (end 0.499 -0.249) (layer "B.Fab") (width 0.15) (fill none))
    (pad "1" smd roundrect (at -0.484 0) (size 0.59 0.64) (layers "B.Cu" "B.Paste" "B.Mask") (roundrect_rratio 0.25)
      (net 229 "/USB-C Interface /DBG_USB_D_N") (pintype "passive"))
    (pad "2" smd roundrect (at 0.484 0) (size 0.59 0.64) (layers "B.Cu" "B.Paste" "B.Mask") (roundrect_rratio 0.25)
      (net 1 "GND") (pintype "passive"))
  )
	(footprint "sa800u-baseboard-hw-footprints:C_0603_1608Metric" (layer "B.Cu")
    (tedit 5D5E94D2)
    (at 127.7 135.35 -90)
    (descr "Capacitor SMD 0603")
    (tags "capacitor 0603")
    (property "Author" "Antmicro")
    (property "Dielectric" "")
    (property "License" "Apache-2.0")
    (property "MPN" "0603YD105KAT2A")
    (property "Manufacturer" "Walsin")
    (property "Sheetfile" "usb-c-interface.kicad_sch")
    (property "Sheetname" "USB-C Interface ")
    (property "Val" "1u")
    (property "Voltage" "")
    (attr smd)
    (fp_text reference "C75" (at -1.18 -1.37 90) (layer "B.SilkS")
      (effects (font (size 0.7 0.7) (thickness 0.15)) (justify left bottom mirror))
    )
    (fp_text value "C_1u_0603" (at 0 -1.6 90) (layer "B.Fab")
      (effects (font (size 0.7 0.7) (thickness 0.15)) (justify left bottom mirror))
    )
    (fp_text user "Author: Antmicro" (at -1.682 -4.894 90) (layer "B.Fab") hide
      (effects (font (size 0.7 0.7) (thickness 0.15)) (justify left bottom mirror))
    )
    (fp_text user "${REFERENCE}" (at -1.682 -3.895 90) (layer "B.Fab") hide
      (effects (font (size 0.7 0.7) (thickness 0.15)) (justify left bottom mirror))
    )
    (fp_text user "License: Apache-2.0" (at -1.682 -5.895 90) (layer "B.Fab") hide
      (effects (font (size 0.7 0.7) (thickness 0.15)) (justify left bottom mirror))
    )
    (fp_line (start -0.3 -0.3) (end 0.3 -0.3) (layer "B.SilkS") (width 0.15))
    (fp_line (start -0.3 0.3) (end 0.3 0.3) (layer "B.SilkS") (width 0.15))
    (fp_rect (start -1.24 0.7) (end 1.24 -0.7) (layer "B.CrtYd") (width 0.05) (fill none))
    (fp_rect (start -0.8 0.4) (end 0.8 -0.4) (layer "B.Fab") (width 0.15) (fill none))
    (pad "1" smd roundrect (at -0.7 0 270) (size 0.6 0.8) (layers "B.Cu" "B.Paste" "B.Mask") (roundrect_rratio 0.2)
      (net 127 "1V8_DBG") (pintype "passive"))
    (pad "2" smd roundrect (at 0.7 0 270) (size 0.6 0.8) (layers "B.Cu" "B.Paste" "B.Mask") (roundrect_rratio 0.2)
      (net 1 "GND") (pintype "passive"))
  )
	(footprint "sa800u-baseboard-hw-footprints:SOT-23-5" (layer "B.Cu")
    (tedit 5D64D240)
    (at 125.1 136.65 90)
    (property "Author" "Antmicro")
    (property "License" "Apache-2.0")
    (property "MPN" "TPS7A0518PDBVT")
    (property "Manufacturer" "Texas Instruments")
    (property "Sheetfile" "usb-c-interface.kicad_sch")
    (property "Sheetname" "USB-C Interface ")
    (attr smd)
    (fp_text reference "IC1" (at -1 -1.9 90) (layer "B.SilkS")
      (effects (font (size 0.7 0.7) (thickness 0.15)) (justify right bottom mirror))
    )
    (fp_text value "TPS7A0518P_SOT23-5" (at 0.002 -2.799 90) (layer "B.Fab")
      (effects (font (size 0.7 0.7) (thickness 0.15)) (justify right bottom mirror))
    )
    (fp_text user "License: Apache-2.0" (at -1.898 -6.7 90) (layer "B.Fab") hide
      (effects (font (size 0.7 0.7) (thickness 0.15)) (justify right bottom mirror))
    )
    (fp_text user "${REFERENCE}" (at -1.898 -4.299 90) (layer "B.Fab") hide
      (effects (font (size 0.7 0.7) (thickness 0.15)) (justify right bottom mirror))
    )
    (fp_text user "Author: Antmicro" (at -1.898 -5.499 90) (layer "B.Fab") hide
      (effects (font (size 0.7 0.7) (thickness 0.15)) (justify right bottom mirror))
    )
    (fp_line (start 0.8 -0.55) (end 0.8 0.55) (layer "B.SilkS") (width 0.15))
    (fp_line (start 0.8 1.3) (end 0.8 1.6) (layer "B.SilkS") (width 0.15))
    (fp_line (start 0.8 -1.3) (end 0.8 -1.599) (layer "B.SilkS") (width 0.15))
    (fp_line (start -0.8 1.6) (end -0.5 1.6) (layer "B.SilkS") (width 0.15))
    (fp_line (start -0.85 -1.6) (end -0.85 -1.301) (layer "B.SilkS") (width 0.15))
    (fp_line (start -0.8 1.6) (end -0.8 1.3) (layer "B.SilkS") (width 0.15))
    (fp_line (start 0.8 -1.599) (end 0.549 -1.599) (layer "B.SilkS") (width 0.15))
    (fp_line (start -0.55 -1.6) (end -0.85 -1.6) (layer "B.SilkS") (width 0.15))
    (fp_line (start 0.8 1.6) (end 0.5 1.6) (layer "B.SilkS") (width 0.15))
    (fp_circle (center -1.25 1.5) (end -1.2 1.5) (layer "B.SilkS") (width 0.15) (fill solid))
    (fp_rect (start 1.9 1.76) (end -1.9 -1.75) (layer "B.CrtYd") (width 0.05) (fill none))
    (fp_line (start -0.398 1.526) (end -0.874 1.05) (layer "B.Fab") (width 0.15))
    (fp_rect (start 0.874 -1.523) (end -0.873 1.525) (layer "B.Fab") (width 0.15) (fill none))
    (pad "1" smd rect (at -1.351 0.951 180) (size 0.55 1) (layers "B.Cu" "B.Paste" "B.Mask")
      (net 228 "/USB-C Interface /5V0_DBG") (pinfunction "VIN") (pintype "power_in"))
    (pad "2" smd rect (at -1.351 0 180) (size 0.55 1) (layers "B.Cu" "B.Paste" "B.Mask")
      (net 1 "GND") (pinfunction "GND") (pintype "power_in"))
    (pad "3" smd rect (at -1.351 -0.949 180) (size 0.55 1) (layers "B.Cu" "B.Paste" "B.Mask")
      (net 228 "/USB-C Interface /5V0_DBG") (pinfunction "EN") (pintype "input"))
    (pad "4" smd rect (at 1.35 -0.949 180) (size 0.55 1) (layers "B.Cu" "B.Paste" "B.Mask")
      (net 413 "unconnected-(IC1-Pad4)") (pinfunction "NC") (pintype "no_connect"))
    (pad "5" smd rect (at 1.35 0.951 180) (size 0.55 1) (layers "B.Cu" "B.Paste" "B.Mask")
      (net 127 "1V8_DBG") (pinfunction "VOUT") (pintype "power_out"))
  )
)
